(kicad_pcb
	(version 20260206)
	(generator "pcbnew")
	(generator_version "10.0")
	(general
		(thickness 1.6)
		(legacy_teardrops no)
	)
	(paper "A4")
	(title_block
		(title "peb — Lightning_PEB_BRD.brd")
		(comment 1 "Lightning (Wiwynn / Facebook NVMe JBOF) / footprints 1791-1798 of 2563")
	)
	(layers
		(0 "F.Cu" signal "TOP")
		(4 "In1.Cu" signal "L2GND")
		(6 "In2.Cu" signal "L3")
		(8 "In3.Cu" signal "L4VCC")
		(10 "In4.Cu" signal "L5VCC")
		(12 "In5.Cu" signal "L6")
		(14 "In6.Cu" signal "L7GND")
		(2 "B.Cu" signal "BOTTOM")
		(9 "F.Adhes" user "F.Adhesive")
		(11 "B.Adhes" user "B.Adhesive")
		(13 "F.Paste" user "Package Geometry/Pastemask Top")
		(15 "B.Paste" user "Package Geometry/Pastemask Bottom")
		(5 "F.SilkS" user "Ref Des/Silkscreen Top")
		(7 "B.SilkS" user "Ref Des/Silkscreen Bottom")
		(1 "F.Mask" user "Board Geometry/Soldermask Top")
		(3 "B.Mask" user "Board Geometry/Soldermask Bottom")
		(17 "Dwgs.User" user "User.Drawings")
		(19 "Cmts.User" user "User.Comments")
		(21 "Eco1.User" user "User.Eco1")
		(23 "Eco2.User" user "User.Eco2")
		(25 "Edge.Cuts" user "Board Geometry/Outline")
		(27 "Margin" user)
		(31 "F.CrtYd" user "Package Geometry/Place Bound Top")
		(29 "B.CrtYd" user "Package Geometry/Place Bound Bottom")
		(35 "F.Fab" user "Ref Des/Assembly Top")
		(33 "B.Fab" user "Ref Des/Assembly Bottom")
	)
	(footprint ""
		(layer "B.Cu")
		(at 80.518 -189.611)
		(property "Reference" "R158"
			(at 0 0 0)
			(layer "B.SilkS")
			(hide yes)
			(effects
				(font
					(size 1.27 1.27)
				)
				(justify mirror)
			)
		)
		(property "Value" "4K7R2F-GP"
			(at -0.064008 -3.993896 0)
			(unlocked yes)
			(layer "B.Fab")
			(hide yes)
			(effects
				(font
					(size 1.016 1.016)
					(thickness 0.1524)
				)
				(justify mirror)
			)
		)
		(property "Device Type" "R402H16"
			(at -0.064008 -5.517896 0)
			(unlocked yes)
			(layer "B.Fab")
			(hide yes)
			(effects
				(font
					(size 1.016 1.016)
					(thickness 0.1524)
				)
				(justify mirror)
			)
		)
		(duplicate_pad_numbers_are_jumpers no)
		(fp_line
			(start -0.508 -0.9398)
			(end 0.508 -0.9398)
			(stroke
				(width 0.1524)
				(type default)
			)
			(layer "B.SilkS")
		)
		(fp_line
			(start 0.508 -0.9398)
			(end 0.508 0.9398)
			(stroke
				(width 0.1524)
				(type default)
			)
			(layer "B.SilkS")
		)
		(fp_rect
			(start 0.508 0.9398)
			(end -0.508 -0.9398)
			(stroke
				(width 0)
				(type default)
			)
			(fill no)
			(layer "B.CrtYd")
		)
		(fp_rect
			(start 0.508 0.9398)
			(end -0.508 -0.9398)
			(stroke
				(width 0)
				(type default)
			)
			(fill no)
			(layer "B.Fab")
		)
		(pad "1" smd custom
			(at 0 -0.4445 180)
			(size 0.1397 0.1397)
			(layers "B.Cu" "B.Mask" "B.Paste")
			(net "BMC_SSD_RST#0_A10")
			(options
				(clearance outline)
				(anchor circle)
			)
			(primitives
				(gr_poly
					(pts
						(arc
							(start -0.1778 0.2794)
							(mid -0.249642 0.249642)
							(end -0.2794 0.1778)
						)
						(arc
							(start -0.2794 -0.1778)
							(mid -0.249642 -0.249642)
							(end -0.1778 -0.2794)
						)
						(arc
							(start 0.1778 -0.2794)
							(mid 0.249642 -0.249642)
							(end 0.2794 -0.1778)
						)
						(arc
							(start 0.2794 0.1778)
							(mid 0.249642 0.249642)
							(end 0.1778 0.2794)
						)
					)
					(width 0)
					(fill yes)
				)
			)
		)
		(pad "2" smd custom
			(at 0 0.4445 180)
			(size 0.1397 0.1397)
			(layers "B.Cu" "B.Mask" "B.Paste")
			(net "P3V3_STBY")
			(options
				(clearance outline)
				(anchor circle)
			)
			(primitives
				(gr_poly
					(pts
						(arc
							(start -0.1778 0.2794)
							(mid -0.249642 0.249642)
							(end -0.2794 0.1778)
						)
						(arc
							(start -0.2794 -0.1778)
							(mid -0.249642 -0.249642)
							(end -0.1778 -0.2794)
						)
						(arc
							(start 0.1778 -0.2794)
							(mid 0.249642 -0.249642)
							(end 0.2794 -0.1778)
						)
						(arc
							(start 0.2794 0.1778)
							(mid 0.249642 0.249642)
							(end 0.1778 0.2794)
						)
					)
					(width 0)
					(fill yes)
				)
			)
		)
	)
	(footprint ""
		(layer "B.Cu")
		(at 58.565034 -118.876318 180)
		(property "Reference" "R520"
			(at 0 0 0)
			(layer "B.SilkS")
			(hide yes)
			(effects
				(font
					(size 1.27 1.27)
				)
				(justify mirror)
			)
		)
		(property "Value" "4K7R2F-GP"
			(at -0.064008 -3.993896 180)
			(unlocked yes)
			(layer "B.Fab")
			(hide yes)
			(effects
				(font
					(size 1.016 1.016)
					(thickness 0.1524)
				)
				(justify mirror)
			)
		)
		(property "Device Type" "R402H16"
			(at -0.064008 -5.517896 180)
			(unlocked yes)
			(layer "B.Fab")
			(hide yes)
			(effects
				(font
					(size 1.016 1.016)
					(thickness 0.1524)
				)
				(justify mirror)
			)
		)
		(duplicate_pad_numbers_are_jumpers no)
		(fp_line
			(start 0.508 -0.9398)
			(end 0.508 0.9398)
			(stroke
				(width 0.1524)
				(type default)
			)
			(layer "B.SilkS")
		)
		(fp_line
			(start -0.508 -0.9398)
			(end 0.508 -0.9398)
			(stroke
				(width 0.1524)
				(type default)
			)
			(layer "B.SilkS")
		)
		(fp_rect
			(start 0.508 0.9398)
			(end -0.508 -0.9398)
			(stroke
				(width 0)
				(type default)
			)
			(fill no)
			(layer "B.CrtYd")
		)
		(fp_rect
			(start 0.508 0.9398)
			(end -0.508 -0.9398)
			(stroke
				(width 0)
				(type default)
			)
			(fill no)
			(layer "B.Fab")
		)
		(pad "1" smd custom
			(at 0 -0.4445)
			(size 0.1397 0.1397)
			(layers "B.Cu" "B.Mask" "B.Paste")
			(net "BMC_I2C3_MINI3_SDA_S")
			(options
				(clearance outline)
				(anchor circle)
			)
			(primitives
				(gr_poly
					(pts
						(arc
							(start -0.1778 0.2794)
							(mid -0.249642 0.249642)
							(end -0.2794 0.1778)
						)
						(arc
							(start -0.2794 -0.1778)
							(mid -0.249642 -0.249642)
							(end -0.1778 -0.2794)
						)
						(arc
							(start 0.1778 -0.2794)
							(mid 0.249642 -0.249642)
							(end 0.2794 -0.1778)
						)
						(arc
							(start 0.2794 0.1778)
							(mid 0.249642 0.249642)
							(end 0.1778 0.2794)
						)
					)
					(width 0)
					(fill yes)
				)
			)
		)
		(pad "2" smd custom
			(at 0 0.4445)
			(size 0.1397 0.1397)
			(layers "B.Cu" "B.Mask" "B.Paste")
			(net "P3V3_STBY")
			(options
				(clearance outline)
				(anchor circle)
			)
			(primitives
				(gr_poly
					(pts
						(arc
							(start -0.1778 0.2794)
							(mid -0.249642 0.249642)
							(end -0.2794 0.1778)
						)
						(arc
							(start -0.2794 -0.1778)
							(mid -0.249642 -0.249642)
							(end -0.1778 -0.2794)
						)
						(arc
							(start 0.1778 -0.2794)
							(mid 0.249642 -0.249642)
							(end 0.2794 -0.1778)
						)
						(arc
							(start 0.2794 0.1778)
							(mid 0.249642 0.249642)
							(end 0.1778 0.2794)
						)
					)
					(width 0)
					(fill yes)
				)
			)
		)
	)
	(footprint ""
		(layer "B.Cu")
		(at 157.492192 -33.589976)
		(property "Reference" "R2932"
			(at 0 0 0)
			(layer "B.SilkS")
			(hide yes)
			(effects
				(font
					(size 1.27 1.27)
				)
				(justify mirror)
			)
		)
		(property "Value" "0R2J-2-GP"
			(at -0.064008 -3.993896 0)
			(unlocked yes)
			(layer "B.Fab")
			(hide yes)
			(effects
				(font
					(size 1.016 1.016)
					(thickness 0.1524)
				)
				(justify mirror)
			)
		)
		(property "Device Type" "R402H16"
			(at -0.064008 -5.517896 0)
			(unlocked yes)
			(layer "B.Fab")
			(hide yes)
			(effects
				(font
					(size 1.016 1.016)
					(thickness 0.1524)
				)
				(justify mirror)
			)
		)
		(duplicate_pad_numbers_are_jumpers no)
		(fp_line
			(start -0.508 -0.9398)
			(end 0.508 -0.9398)
			(stroke
				(width 0.1524)
				(type default)
			)
			(layer "B.SilkS")
		)
		(fp_line
			(start 0.508 -0.9398)
			(end 0.508 0.9398)
			(stroke
				(width 0.1524)
				(type default)
			)
			(layer "B.SilkS")
		)
		(fp_rect
			(start 0.508 0.9398)
			(end -0.508 -0.9398)
			(stroke
				(width 0)
				(type default)
			)
			(fill no)
			(layer "B.CrtYd")
		)
		(fp_rect
			(start 0.508 0.9398)
			(end -0.508 -0.9398)
			(stroke
				(width 0)
				(type default)
			)
			(fill no)
			(layer "B.Fab")
		)
		(pad "1" smd custom
			(at 0 -0.4445 180)
			(size 0.1397 0.1397)
			(layers "B.Cu" "B.Mask" "B.Paste")
			(net "BMC_I2C3_MINI3_SDA")
			(options
				(clearance outline)
				(anchor circle)
			)
			(primitives
				(gr_poly
					(pts
						(arc
							(start -0.1778 0.2794)
							(mid -0.249642 0.249642)
							(end -0.2794 0.1778)
						)
						(arc
							(start -0.2794 -0.1778)
							(mid -0.249642 -0.249642)
							(end -0.1778 -0.2794)
						)
						(arc
							(start 0.1778 -0.2794)
							(mid 0.249642 -0.249642)
							(end 0.2794 -0.1778)
						)
						(arc
							(start 0.2794 0.1778)
							(mid 0.249642 0.249642)
							(end 0.1778 0.2794)
						)
					)
					(width 0)
					(fill yes)
				)
			)
		)
		(pad "2" smd custom
			(at 0 0.4445 180)
			(size 0.1397 0.1397)
			(layers "B.Cu" "B.Mask" "B.Paste")
			(net "8644_CBL_PRSNT_R_3")
			(options
				(clearance outline)
				(anchor circle)
			)
			(primitives
				(gr_poly
					(pts
						(arc
							(start -0.1778 0.2794)
							(mid -0.249642 0.249642)
							(end -0.2794 0.1778)
						)
						(arc
							(start -0.2794 -0.1778)
							(mid -0.249642 -0.249642)
							(end -0.1778 -0.2794)
						)
						(arc
							(start 0.1778 -0.2794)
							(mid 0.249642 -0.249642)
							(end 0.2794 -0.1778)
						)
						(arc
							(start 0.2794 0.1778)
							(mid 0.249642 0.249642)
							(end 0.1778 0.2794)
						)
					)
					(width 0)
					(fill yes)
				)
			)
		)
	)
	(footprint ""
		(layer "B.Cu")
		(at 237.1598 -48.9966 90)
		(property "Reference" "C31"
			(at 0 0 90)
			(layer "B.SilkS")
			(hide yes)
			(effects
				(font
					(size 1.27 1.27)
				)
				(justify mirror)
			)
		)
		(property "Value" "SCD1U16V1KX-1-GP"
			(at 2.8321 -1.7399 90)
			(unlocked yes)
			(layer "B.Fab")
			(hide yes)
			(effects
				(font
					(size 1.016 1.016)
					(thickness 0.1524)
				)
				(justify mirror)
			)
		)
		(property "Device Type" "C0201H13"
			(at 2.8321 -3.2639 90)
			(unlocked yes)
			(layer "B.Fab")
			(hide yes)
			(effects
				(font
					(size 1.016 1.016)
					(thickness 0.1524)
				)
				(justify mirror)
			)
		)
		(duplicate_pad_numbers_are_jumpers no)
		(fp_rect
			(start 0.2794 0.6477)
			(end -0.2794 -0.6477)
			(stroke
				(width 0)
				(type default)
			)
			(fill no)
			(layer "B.CrtYd")
		)
		(fp_rect
			(start 0.2794 0.6477)
			(end -0.2794 -0.6477)
			(stroke
				(width 0)
				(type default)
			)
			(fill no)
			(layer "B.Fab")
		)
		(pad "1" smd custom
			(at 0 -0.2794 270)
			(size 0.0762 0.0762)
			(layers "B.Cu" "B.Mask" "B.Paste")
			(net "DUT_VDD")
			(options
				(clearance outline)
				(anchor circle)
			)
			(primitives
				(gr_poly
					(pts
						(arc
							(start 0.1524 0.127)
							(mid 0.137521 0.162921)
							(end 0.1016 0.1778)
						)
						(arc
							(start -0.1016 0.1778)
							(mid -0.137521 0.162921)
							(end -0.1524 0.127)
						)
						(arc
							(start -0.1524 -0.127)
							(mid -0.137521 -0.162921)
							(end -0.1016 -0.1778)
						)
						(arc
							(start 0.1016 -0.1778)
							(mid 0.137521 -0.162921)
							(end 0.1524 -0.127)
						)
					)
					(width 0)
					(fill yes)
				)
			)
		)
		(pad "2" smd custom
			(at 0 0.2794 270)
			(size 0.0762 0.0762)
			(layers "B.Cu" "B.Mask" "B.Paste")
			(net "GND")
			(options
				(clearance outline)
				(anchor circle)
			)
			(primitives
				(gr_poly
					(pts
						(arc
							(start 0.1524 0.127)
							(mid 0.137521 0.162921)
							(end 0.1016 0.1778)
						)
						(arc
							(start -0.1016 0.1778)
							(mid -0.137521 0.162921)
							(end -0.1524 0.127)
						)
						(arc
							(start -0.1524 -0.127)
							(mid -0.137521 -0.162921)
							(end -0.1016 -0.1778)
						)
						(arc
							(start 0.1016 -0.1778)
							(mid 0.137521 -0.162921)
							(end 0.1524 -0.127)
						)
					)
					(width 0)
					(fill yes)
				)
			)
		)
	)
	(footprint ""
		(layer "B.Cu")
		(at 251.599954 -33.999932 -90)
		(property "Reference" "TP279"
			(at 0 0 90)
			(layer "B.SilkS")
			(hide yes)
			(effects
				(font
					(size 1.27 1.27)
				)
				(justify mirror)
			)
		)
		(property "Value" "TPAD28-2-GP"
			(at 0.0127 -1.6637 270)
			(unlocked yes)
			(layer "B.Fab")
			(hide yes)
			(effects
				(font
					(size 1.016 1.016)
					(thickness 0.1524)
				)
				(justify mirror)
			)
		)
		(property "Device Type" "TPAD28"
			(at 0.0127 -3.1877 270)
			(unlocked yes)
			(layer "B.Fab")
			(hide yes)
			(effects
				(font
					(size 1.016 1.016)
					(thickness 0.1524)
				)
				(justify mirror)
			)
		)
		(duplicate_pad_numbers_are_jumpers no)
		(fp_poly
			(pts
				(arc
					(start 0 -0.3556)
					(mid 0 0.3556)
					(end 0 -0.3556)
				)
			)
			(stroke
				(width 0)
				(type default)
			)
			(fill no)
			(layer "B.CrtYd")
		)
		(fp_poly
			(pts
				(arc
					(start 0 -0.6096)
					(mid 0 0.6096)
					(end 0 -0.6096)
				)
			)
			(stroke
				(width 0)
				(type default)
			)
			(fill no)
			(layer "B.Fab")
		)
		(pad "1" smd circle
			(at 0 0 90)
			(size 0.7112 0.7112)
			(layers "B.Cu" "B.Mask" "B.Paste")
			(net "TWI_SRST#0")
		)
	)
	(footprint ""
		(layer "B.Cu")
		(at 15.4686 -80.0354 90)
		(property "Reference" "C633"
			(at 0 0 90)
			(layer "B.SilkS")
			(hide yes)
			(effects
				(font
					(size 1.27 1.27)
				)
				(justify mirror)
			)
		)
		(property "Value" "SC47U4V5MX-2-GP"
			(at 0.0762 -6.1214 90)
			(unlocked yes)
			(layer "B.Fab")
			(hide yes)
			(effects
				(font
					(size 1.016 1.016)
					(thickness 0.1524)
				)
				(justify mirror)
			)
		)
		(property "Device Type" "C805H58"
			(at 0.0762 -8.1534 90)
			(unlocked yes)
			(layer "B.Fab")
			(hide yes)
			(effects
				(font
					(size 1.016 1.016)
					(thickness 0.1524)
				)
				(justify mirror)
			)
		)
		(duplicate_pad_numbers_are_jumpers no)
		(fp_line
			(start -0.635 0)
			(end 0.635 0)
			(stroke
				(width 0.508)
				(type default)
			)
			(layer "B.SilkS")
		)
		(fp_rect
			(start 0.9652 1.778)
			(end -0.9652 -1.778)
			(stroke
				(width 0)
				(type default)
			)
			(fill no)
			(layer "B.CrtYd")
		)
		(fp_poly
			(pts
				(xy 0.9652 -1.778) (xy -0.9652 -1.778) (xy -0.9652 1.778) (xy 0.9652 1.778)
			)
			(stroke
				(width 0)
				(type default)
			)
			(fill no)
			(layer "B.Fab")
		)
		(pad "1" smd rect
			(at 0 -0.9652 270)
			(size 1.397 1.143)
			(layers "B.Cu" "B.Mask" "B.Paste")
			(net "P0V9_I210")
		)
		(pad "2" smd rect
			(at 0 0.9652 270)
			(size 1.397 1.143)
			(layers "B.Cu" "B.Mask" "B.Paste")
			(net "GND")
		)
	)
	(footprint ""
		(layer "B.Cu")
		(at 59.218322 -121.368566 90)
		(property "Reference" "R492"
			(at 0 0 90)
			(layer "B.SilkS")
			(hide yes)
			(effects
				(font
					(size 1.27 1.27)
				)
				(justify mirror)
			)
		)
		(property "Value" "2K2R2J-2-GP"
			(at -0.064008 -3.993896 90)
			(unlocked yes)
			(layer "B.Fab")
			(hide yes)
			(effects
				(font
					(size 1.016 1.016)
					(thickness 0.1524)
				)
				(justify mirror)
			)
		)
		(property "Device Type" "R402H16"
			(at -0.064008 -5.517896 90)
			(unlocked yes)
			(layer "B.Fab")
			(hide yes)
			(effects
				(font
					(size 1.016 1.016)
					(thickness 0.1524)
				)
				(justify mirror)
			)
		)
		(duplicate_pad_numbers_are_jumpers no)
		(fp_line
			(start 0.508 -0.9398)
			(end 0.508 0.9398)
			(stroke
				(width 0.1524)
				(type default)
			)
			(layer "B.SilkS")
		)
		(fp_line
			(start -0.508 -0.9398)
			(end 0.508 -0.9398)
			(stroke
				(width 0.1524)
				(type default)
			)
			(layer "B.SilkS")
		)
		(fp_rect
			(start 0.508 0.9398)
			(end -0.508 -0.9398)
			(stroke
				(width 0)
				(type default)
			)
			(fill no)
			(layer "B.CrtYd")
		)
		(fp_rect
			(start 0.508 0.9398)
			(end -0.508 -0.9398)
			(stroke
				(width 0)
				(type default)
			)
			(fill no)
			(layer "B.Fab")
		)
		(pad "1" smd custom
			(at 0 -0.4445 270)
			(size 0.1397 0.1397)
			(layers "B.Cu" "B.Mask" "B.Paste")
			(net "BMC_I2C5_D_PEB_DEVICE_SCL")
			(options
				(clearance outline)
				(anchor circle)
			)
			(primitives
				(gr_poly
					(pts
						(arc
							(start -0.1778 0.2794)
							(mid -0.249642 0.249642)
							(end -0.2794 0.1778)
						)
						(arc
							(start -0.2794 -0.1778)
							(mid -0.249642 -0.249642)
							(end -0.1778 -0.2794)
						)
						(arc
							(start 0.1778 -0.2794)
							(mid 0.249642 -0.249642)
							(end 0.2794 -0.1778)
						)
						(arc
							(start 0.2794 0.1778)
							(mid 0.249642 0.249642)
							(end 0.1778 0.2794)
						)
					)
					(width 0)
					(fill yes)
				)
			)
		)
		(pad "2" smd custom
			(at 0 0.4445 270)
			(size 0.1397 0.1397)
			(layers "B.Cu" "B.Mask" "B.Paste")
			(net "P3V3_STBY")
			(options
				(clearance outline)
				(anchor circle)
			)
			(primitives
				(gr_poly
					(pts
						(arc
							(start -0.1778 0.2794)
							(mid -0.249642 0.249642)
							(end -0.2794 0.1778)
						)
						(arc
							(start -0.2794 -0.1778)
							(mid -0.249642 -0.249642)
							(end -0.1778 -0.2794)
						)
						(arc
							(start 0.1778 -0.2794)
							(mid 0.249642 -0.249642)
							(end 0.2794 -0.1778)
						)
						(arc
							(start 0.2794 0.1778)
							(mid 0.249642 0.249642)
							(end 0.1778 0.2794)
						)
					)
					(width 0)
					(fill yes)
				)
			)
		)
	)
	(footprint ""
		(layer "B.Cu")
		(at 79.039212 -192.641474)
		(property "Reference" "R3216"
			(at 0 0 0)
			(layer "B.SilkS")
			(hide yes)
			(effects
				(font
					(size 1.27 1.27)
				)
				(justify mirror)
			)
		)
		(property "Value" "0R2J-2-GP"
			(at -0.064008 -3.993896 0)
			(unlocked yes)
			(layer "B.Fab")
			(hide yes)
			(effects
				(font
					(size 1.016 1.016)
					(thickness 0.1524)
				)
				(justify mirror)
			)
		)
		(property "Device Type" "R402H16"
			(at -0.064008 -5.517896 0)
			(unlocked yes)
			(layer "B.Fab")
			(hide yes)
			(effects
				(font
					(size 1.016 1.016)
					(thickness 0.1524)
				)
				(justify mirror)
			)
		)
		(duplicate_pad_numbers_are_jumpers no)
		(fp_line
			(start -0.508 -0.9398)
			(end 0.508 -0.9398)
			(stroke
				(width 0.1524)
				(type default)
			)
			(layer "B.SilkS")
		)
		(fp_line
			(start 0.508 -0.9398)
			(end 0.508 0.9398)
			(stroke
				(width 0.1524)
				(type default)
			)
			(layer "B.SilkS")
		)
		(fp_rect
			(start 0.508 0.9398)
			(end -0.508 -0.9398)
			(stroke
				(width 0)
				(type default)
			)
			(fill no)
			(layer "B.CrtYd")
		)
		(fp_rect
			(start 0.508 0.9398)
			(end -0.508 -0.9398)
			(stroke
				(width 0)
				(type default)
			)
			(fill no)
			(layer "B.Fab")
		)
		(pad "1" smd custom
			(at 0 -0.4445 180)
			(size 0.1397 0.1397)
			(layers "B.Cu" "B.Mask" "B.Paste")
			(net "SSD_PERST#5")
			(options
				(clearance outline)
				(anchor circle)
			)
			(primitives
				(gr_poly
					(pts
						(arc
							(start -0.1778 0.2794)
							(mid -0.249642 0.249642)
							(end -0.2794 0.1778)
						)
						(arc
							(start -0.2794 -0.1778)
							(mid -0.249642 -0.249642)
							(end -0.1778 -0.2794)
						)
						(arc
							(start 0.1778 -0.2794)
							(mid 0.249642 -0.249642)
							(end 0.2794 -0.1778)
						)
						(arc
							(start 0.2794 0.1778)
							(mid 0.249642 0.249642)
							(end 0.1778 0.2794)
						)
					)
					(width 0)
					(fill yes)
				)
			)
		)
		(pad "2" smd custom
			(at 0 0.4445 180)
			(size 0.1397 0.1397)
			(layers "B.Cu" "B.Mask" "B.Paste")
			(net "SSD_PERST#0_B5")
			(options
				(clearance outline)
				(anchor circle)
			)
			(primitives
				(gr_poly
					(pts
						(arc
							(start -0.1778 0.2794)
							(mid -0.249642 0.249642)
							(end -0.2794 0.1778)
						)
						(arc
							(start -0.2794 -0.1778)
							(mid -0.249642 -0.249642)
							(end -0.1778 -0.2794)
						)
						(arc
							(start 0.1778 -0.2794)
							(mid 0.249642 -0.249642)
							(end 0.2794 -0.1778)
						)
						(arc
							(start 0.2794 0.1778)
							(mid 0.249642 0.249642)
							(end 0.1778 0.2794)
						)
					)
					(width 0)
					(fill yes)
				)
			)
		)
	)
)
